# SCM (Grand Teton) — schematic netlist excerpt (pin names and nets, part order shuffled) for the footprints in the layout excerpt that follows; sources: Cadence DE-HDL packaged netlist, KiCad conversion of 12092022_DA0F0TMDCD0_F0T_Management_Board_D_brd_V3_OCP.brd

C173  Q_CAP  2200PF 50V 10% X7R  pkg 0402  page 22 : A = RST_BMC_SELF_HW_D_C ; B = GND
PR525  Q_RES  20.5K 1% CHIP  pkg 0402LF  page 51 : A = P5V_AUX_CS ; B = GND

(kicad_pcb
	(version 20260206)
	(generator "pcbnew")
	(generator_version "10.0")
	(general
		(thickness 1.6)
		(legacy_teardrops no)
	)
	(paper "A4")
	(title_block
		(title "12092022_DA0F0TMDCD0_F0T_Management_Board_D_brd_V3_OCP.brd")
		(comment 1 "Grand Teton / footprints 450-451 of 1440")
	)
	(layers
		(0 "F.Cu" signal "TOP")
		(4 "In1.Cu" signal "GND")
		(6 "In2.Cu" signal "IN1")
		(8 "In3.Cu" signal "GND1")
		(10 "In4.Cu" signal "IN2")
		(12 "In5.Cu" signal "VCC")
		(14 "In6.Cu" signal "VCC1")
		(16 "In7.Cu" signal "IN3")
		(18 "In8.Cu" signal "GND2")
		(20 "In9.Cu" signal "IN4")
		(22 "In10.Cu" signal "GND3")
		(2 "B.Cu" signal "BOTTOM")
		(9 "F.Adhes" user "F.Adhesive")
		(11 "B.Adhes" user "B.Adhesive")
		(13 "F.Paste" user "Package Geometry/Pastemask Top")
		(15 "B.Paste" user "Package Geometry/Pastemask Bottom")
		(5 "F.SilkS" user "Ref Des/Silkscreen Top")
		(7 "B.SilkS" user "Ref Des/Silkscreen Bottom")
		(1 "F.Mask" user "Board Geometry/Soldermask Top")
		(3 "B.Mask" user "Board Geometry/Soldermask Bottom")
		(17 "Dwgs.User" user "User.Drawings")
		(19 "Cmts.User" user "User.Comments")
		(21 "Eco1.User" user "User.Eco1")
		(23 "Eco2.User" user "User.Eco2")
		(25 "Edge.Cuts" user "Board Geometry/Outline")
		(27 "Margin" user)
		(31 "F.CrtYd" user "Package Geometry/Place Bound Top")
		(29 "B.CrtYd" user "Package Geometry/Place Bound Bottom")
		(35 "F.Fab" user "Ref Des/Assembly Top")
		(33 "B.Fab" user "Ref Des/Assembly Bottom")
	)
	(footprint ""
		(layer "F.Cu")
		(at 23.1775 -104.775)
		(property "Reference" "C173"
			(at 0 0 0)
			(layer "F.SilkS")
			(hide yes)
			(effects
				(font
					(size 1.27 1.27)
				)
			)
		)
		(property "Value" ""
			(at 0 0 0)
			(layer "F.Fab")
			(effects
				(font
					(size 1.27 1.27)
				)
			)
		)
		(duplicate_pad_numbers_are_jumpers no)
		(fp_line
			(start -0.7874 -0.4064)
			(end 0.7874 -0.4064)
			(stroke
				(width 0.1524)
				(type default)
			)
			(layer "F.SilkS")
		)
		(fp_line
			(start -0.7874 0.4064)
			(end -0.7874 -0.4064)
			(stroke
				(width 0.1524)
				(type default)
			)
			(layer "F.SilkS")
		)
		(fp_line
			(start 0.7874 -0.4064)
			(end 0.7874 0.4064)
			(stroke
				(width 0.1524)
				(type default)
			)
			(layer "F.SilkS")
		)
		(fp_line
			(start 0.7874 0.4064)
			(end -0.7874 0.4064)
			(stroke
				(width 0.1524)
				(type default)
			)
			(layer "F.SilkS")
		)
		(fp_line
			(start -0.67945 -0.305054)
			(end -0.12065 -0.305054)
			(stroke
				(width 0.1)
				(type default)
			)
			(layer "F.Fab")
		)
		(fp_line
			(start -0.67945 0.3048)
			(end -0.67945 -0.305054)
			(stroke
				(width 0.1)
				(type default)
			)
			(layer "F.Fab")
		)
		(fp_line
			(start -0.12065 -0.305054)
			(end -0.12065 -0.2794)
			(stroke
				(width 0.1)
				(type default)
			)
			(layer "F.Fab")
		)
		(fp_line
			(start -0.12065 -0.2794)
			(end 0.12065 -0.2794)
			(stroke
				(width 0.1)
				(type default)
			)
			(layer "F.Fab")
		)
		(fp_line
			(start -0.12065 0.2794)
			(end -0.12065 0.3048)
			(stroke
				(width 0.1)
				(type default)
			)
			(layer "F.Fab")
		)
		(fp_line
			(start -0.12065 0.3048)
			(end -0.67945 0.3048)
			(stroke
				(width 0.1)
				(type default)
			)
			(layer "F.Fab")
		)
		(fp_line
			(start 0.120396 0.2794)
			(end -0.12065 0.2794)
			(stroke
				(width 0.1)
				(type default)
			)
			(layer "F.Fab")
		)
		(fp_line
			(start 0.120396 0.3048)
			(end 0.120396 0.2794)
			(stroke
				(width 0.1)
				(type default)
			)
			(layer "F.Fab")
		)
		(fp_line
			(start 0.12065 -0.3048)
			(end 0.67945 -0.3048)
			(stroke
				(width 0.1)
				(type default)
			)
			(layer "F.Fab")
		)
		(fp_line
			(start 0.12065 -0.2794)
			(end 0.12065 -0.3048)
			(stroke
				(width 0.1)
				(type default)
			)
			(layer "F.Fab")
		)
		(fp_line
			(start 0.67945 -0.3048)
			(end 0.67945 0.3048)
			(stroke
				(width 0.1)
				(type default)
			)
			(layer "F.Fab")
		)
		(fp_line
			(start 0.67945 0.3048)
			(end 0.120396 0.3048)
			(stroke
				(width 0.1)
				(type default)
			)
			(layer "F.Fab")
		)
		(pad "1" smd circle
			(at -0.40005 0)
			(size 0 0)
			(layers "F.Cu" "F.Mask" "F.Paste")
			(net "RST_BMC_SELF_HW_D_C")
		)
		(pad "2" smd circle
			(at 0.40005 0)
			(size 0 0)
			(layers "F.Cu" "F.Mask" "F.Paste")
			(net "GND")
		)
	)
	(footprint ""
		(layer "F.Cu")
		(at 11.612626 -47.63135)
		(property "Reference" "PR525"
			(at 0 0 0)
			(layer "F.SilkS")
			(hide yes)
			(effects
				(font
					(size 1.27 1.27)
				)
			)
		)
		(property "Value" ""
			(at 0 0 0)
			(layer "F.Fab")
			(effects
				(font
					(size 1.27 1.27)
				)
			)
		)
		(duplicate_pad_numbers_are_jumpers no)
		(fp_line
			(start -0.7874 -0.4064)
			(end 0.7874 -0.4064)
			(stroke
				(width 0.1524)
				(type default)
			)
			(layer "F.SilkS")
		)
		(fp_line
			(start -0.7874 0.4064)
			(end -0.7874 -0.4064)
			(stroke
				(width 0.1524)
				(type default)
			)
			(layer "F.SilkS")
		)
		(fp_line
			(start 0.7874 -0.4064)
			(end 0.7874 0.4064)
			(stroke
				(width 0.1524)
				(type default)
			)
			(layer "F.SilkS")
		)
		(fp_line
			(start 0.7874 0.4064)
			(end -0.7874 0.4064)
			(stroke
				(width 0.1524)
				(type default)
			)
			(layer "F.SilkS")
		)
		(fp_line
			(start -0.67945 -0.305054)
			(end -0.12065 -0.305054)
			(stroke
				(width 0.1)
				(type default)
			)
			(layer "F.Fab")
		)
		(fp_line
			(start -0.67945 0.3048)
			(end -0.67945 -0.305054)
			(stroke
				(width 0.1)
				(type default)
			)
			(layer "F.Fab")
		)
		(fp_line
			(start -0.12065 -0.305054)
			(end -0.12065 -0.2794)
			(stroke
				(width 0.1)
				(type default)
			)
			(layer "F.Fab")
		)
		(fp_line
			(start -0.12065 -0.2794)
			(end 0.12065 -0.2794)
			(stroke
				(width 0.1)
				(type default)
			)
			(layer "F.Fab")
		)
		(fp_line
			(start -0.12065 0.2794)
			(end -0.12065 0.3048)
			(stroke
				(width 0.1)
				(type default)
			)
			(layer "F.Fab")
		)
		(fp_line
			(start -0.12065 0.3048)
			(end -0.67945 0.3048)
			(stroke
				(width 0.1)
				(type default)
			)
			(layer "F.Fab")
		)
		(fp_line
			(start 0.120396 0.2794)
			(end -0.12065 0.2794)
			(stroke
				(width 0.1)
				(type default)
			)
			(layer "F.Fab")
		)
		(fp_line
			(start 0.120396 0.3048)
			(end 0.120396 0.2794)
			(stroke
				(width 0.1)
				(type default)
			)
			(layer "F.Fab")
		)
		(fp_line
			(start 0.12065 -0.3048)
			(end 0.67945 -0.3048)
			(stroke
				(width 0.1)
				(type default)
			)
			(layer "F.Fab")
		)
		(fp_line
			(start 0.12065 -0.2794)
			(end 0.12065 -0.3048)
			(stroke
				(width 0.1)
				(type default)
			)
			(layer "F.Fab")
		)
		(fp_line
			(start 0.67945 -0.3048)
			(end 0.67945 0.3048)
			(stroke
				(width 0.1)
				(type default)
			)
			(layer "F.Fab")
		)
		(fp_line
			(start 0.67945 0.3048)
			(end 0.120396 0.3048)
			(stroke
				(width 0.1)
				(type default)
			)
			(layer "F.Fab")
		)
		(pad "1" smd circle
			(at -0.40005 0)
			(size 0 0)
			(layers "F.Cu" "F.Mask" "F.Paste")
			(net "P5V_AUX_CS")
		)
		(pad "2" smd circle
			(at 0.40005 0)
			(size 0 0)
			(layers "F.Cu" "F.Mask" "F.Paste")
			(net "GND")
		)
	)
)
